(kicad_pcb
	(version 20260206)
	(generator "pcbnew")
	(generator_version "10.0")
	(general
		(thickness 1.6)
		(legacy_teardrops no)
	)
	(paper "A4")
	(title_block
		(title "04192023_DAF0TMB3IC0_F0TG_MB_C_brd_V02_OCP.brd")
		(comment 1 "Grand Teton / footprints 5382-5386 of 8354")
	)
	(layers
		(0 "F.Cu" signal "TOP")
		(4 "In1.Cu" signal "GND")
		(6 "In2.Cu" signal "IN1")
		(8 "In3.Cu" signal "GND1")
		(10 "In4.Cu" signal "IN2")
		(12 "In5.Cu" signal "GND2")
		(14 "In6.Cu" signal "IN3")
		(16 "In7.Cu" signal "GND3")
		(18 "In8.Cu" signal "VCC")
		(20 "In9.Cu" signal "VCC1")
		(22 "In10.Cu" signal "GND4")
		(24 "In11.Cu" signal "IN4")
		(26 "In12.Cu" signal "GND5")
		(28 "In13.Cu" signal "IN5")
		(30 "In14.Cu" signal "GND6")
		(32 "In15.Cu" signal "IN6")
		(34 "In16.Cu" signal "GND7")
		(2 "B.Cu" signal "BOTTOM")
		(9 "F.Adhes" user "F.Adhesive")
		(11 "B.Adhes" user "B.Adhesive")
		(13 "F.Paste" user "Package Geometry/Pastemask Top")
		(15 "B.Paste" user "Package Geometry/Pastemask Bottom")
		(5 "F.SilkS" user "Ref Des/Silkscreen Top")
		(7 "B.SilkS" user "Ref Des/Silkscreen Bottom")
		(1 "F.Mask" user "Board Geometry/Soldermask Top")
		(3 "B.Mask" user "Board Geometry/Soldermask Bottom")
		(17 "Dwgs.User" user "User.Drawings")
		(19 "Cmts.User" user "User.Comments")
		(21 "Eco1.User" user "User.Eco1")
		(23 "Eco2.User" user "User.Eco2")
		(25 "Edge.Cuts" user "Board Geometry/Outline")
		(27 "Margin" user)
		(31 "F.CrtYd" user "Package Geometry/Place Bound Top")
		(29 "B.CrtYd" user "Package Geometry/Place Bound Bottom")
		(35 "F.Fab" user "Ref Des/Assembly Top")
		(33 "B.Fab" user "Ref Des/Assembly Bottom")
	)
	(footprint ""
		(layer "B.Cu")
		(at 166.696644 -9.013444 -90)
		(property "Reference" "R2204"
			(at 0 0 90)
			(layer "B.SilkS")
			(hide yes)
			(effects
				(font
					(size 1.27 1.27)
				)
				(justify mirror)
			)
		)
		(property "Value" ""
			(at 0 0 90)
			(layer "B.Fab")
			(effects
				(font
					(size 1.27 1.27)
				)
				(justify mirror)
			)
		)
		(duplicate_pad_numbers_are_jumpers no)
		(fp_line
			(start -0.7874 0.4064)
			(end 0.7874 0.4064)
			(stroke
				(width 0.1524)
				(type default)
			)
			(layer "B.SilkS")
		)
		(fp_line
			(start 0.7874 0.4064)
			(end 0.7874 -0.4064)
			(stroke
				(width 0.1524)
				(type default)
			)
			(layer "B.SilkS")
		)
		(fp_line
			(start -0.7874 -0.4064)
			(end -0.7874 0.4064)
			(stroke
				(width 0.1524)
				(type default)
			)
			(layer "B.SilkS")
		)
		(fp_line
			(start 0.7874 -0.4064)
			(end -0.7874 -0.4064)
			(stroke
				(width 0.1524)
				(type default)
			)
			(layer "B.SilkS")
		)
		(fp_line
			(start -0.67945 0.3048)
			(end -0.120396 0.3048)
			(stroke
				(width 0.1)
				(type default)
			)
			(layer "B.Fab")
		)
		(fp_line
			(start -0.120396 0.3048)
			(end -0.120396 0.2794)
			(stroke
				(width 0.1)
				(type default)
			)
			(layer "B.Fab")
		)
		(fp_line
			(start 0.12065 0.3048)
			(end 0.67945 0.3048)
			(stroke
				(width 0.1)
				(type default)
			)
			(layer "B.Fab")
		)
		(fp_line
			(start 0.67945 0.3048)
			(end 0.67945 -0.305054)
			(stroke
				(width 0.1)
				(type default)
			)
			(layer "B.Fab")
		)
		(fp_line
			(start -0.120396 0.2794)
			(end 0.12065 0.2794)
			(stroke
				(width 0.1)
				(type default)
			)
			(layer "B.Fab")
		)
		(fp_line
			(start 0.12065 0.2794)
			(end 0.12065 0.3048)
			(stroke
				(width 0.1)
				(type default)
			)
			(layer "B.Fab")
		)
		(fp_line
			(start -0.12065 -0.2794)
			(end -0.12065 -0.3048)
			(stroke
				(width 0.1)
				(type default)
			)
			(layer "B.Fab")
		)
		(fp_line
			(start 0.12065 -0.2794)
			(end -0.12065 -0.2794)
			(stroke
				(width 0.1)
				(type default)
			)
			(layer "B.Fab")
		)
		(fp_line
			(start -0.67945 -0.3048)
			(end -0.67945 0.3048)
			(stroke
				(width 0.1)
				(type default)
			)
			(layer "B.Fab")
		)
		(fp_line
			(start -0.12065 -0.3048)
			(end -0.67945 -0.3048)
			(stroke
				(width 0.1)
				(type default)
			)
			(layer "B.Fab")
		)
		(fp_line
			(start 0.12065 -0.305054)
			(end 0.12065 -0.2794)
			(stroke
				(width 0.1)
				(type default)
			)
			(layer "B.Fab")
		)
		(fp_line
			(start 0.67945 -0.305054)
			(end 0.12065 -0.305054)
			(stroke
				(width 0.1)
				(type default)
			)
			(layer "B.Fab")
		)
		(pad "1" smd circle
			(at 0.40005 0 90)
			(size 0 0)
			(layers "B.Cu" "B.Mask" "B.Paste")
			(net "P3V3_AUX")
		)
		(pad "2" smd circle
			(at -0.40005 0 90)
			(size 0 0)
			(layers "B.Cu" "B.Mask" "B.Paste")
			(net "SMB_PCIE0_3V3AUX_SCL")
		)
	)
	(footprint ""
		(layer "B.Cu")
		(at 237.871 -216.027 180)
		(property "Reference" "R361"
			(at 0 0 0)
			(layer "B.SilkS")
			(hide yes)
			(effects
				(font
					(size 1.27 1.27)
				)
				(justify mirror)
			)
		)
		(property "Value" ""
			(at 0 0 0)
			(layer "B.Fab")
			(effects
				(font
					(size 1.27 1.27)
				)
				(justify mirror)
			)
		)
		(duplicate_pad_numbers_are_jumpers no)
		(fp_line
			(start 0.7874 0.4064)
			(end 0.7874 -0.4064)
			(stroke
				(width 0.1524)
				(type default)
			)
			(layer "B.SilkS")
		)
		(fp_line
			(start 0.7874 -0.4064)
			(end -0.7874 -0.4064)
			(stroke
				(width 0.1524)
				(type default)
			)
			(layer "B.SilkS")
		)
		(fp_line
			(start -0.7874 0.4064)
			(end 0.7874 0.4064)
			(stroke
				(width 0.1524)
				(type default)
			)
			(layer "B.SilkS")
		)
		(fp_line
			(start -0.7874 -0.4064)
			(end -0.7874 0.4064)
			(stroke
				(width 0.1524)
				(type default)
			)
			(layer "B.SilkS")
		)
		(fp_line
			(start 0.67945 0.3048)
			(end 0.67945 -0.305054)
			(stroke
				(width 0.1)
				(type default)
			)
			(layer "B.Fab")
		)
		(fp_line
			(start 0.67945 -0.305054)
			(end 0.12065 -0.305054)
			(stroke
				(width 0.1)
				(type default)
			)
			(layer "B.Fab")
		)
		(fp_line
			(start 0.12065 0.3048)
			(end 0.67945 0.3048)
			(stroke
				(width 0.1)
				(type default)
			)
			(layer "B.Fab")
		)
		(fp_line
			(start 0.12065 0.2794)
			(end 0.12065 0.3048)
			(stroke
				(width 0.1)
				(type default)
			)
			(layer "B.Fab")
		)
		(fp_line
			(start 0.12065 -0.2794)
			(end -0.12065 -0.2794)
			(stroke
				(width 0.1)
				(type default)
			)
			(layer "B.Fab")
		)
		(fp_line
			(start 0.12065 -0.305054)
			(end 0.12065 -0.2794)
			(stroke
				(width 0.1)
				(type default)
			)
			(layer "B.Fab")
		)
		(fp_line
			(start -0.120396 0.3048)
			(end -0.120396 0.2794)
			(stroke
				(width 0.1)
				(type default)
			)
			(layer "B.Fab")
		)
		(fp_line
			(start -0.120396 0.2794)
			(end 0.12065 0.2794)
			(stroke
				(width 0.1)
				(type default)
			)
			(layer "B.Fab")
		)
		(fp_line
			(start -0.12065 -0.2794)
			(end -0.12065 -0.3048)
			(stroke
				(width 0.1)
				(type default)
			)
			(layer "B.Fab")
		)
		(fp_line
			(start -0.12065 -0.3048)
			(end -0.67945 -0.3048)
			(stroke
				(width 0.1)
				(type default)
			)
			(layer "B.Fab")
		)
		(fp_line
			(start -0.67945 0.3048)
			(end -0.120396 0.3048)
			(stroke
				(width 0.1)
				(type default)
			)
			(layer "B.Fab")
		)
		(fp_line
			(start -0.67945 -0.3048)
			(end -0.67945 0.3048)
			(stroke
				(width 0.1)
				(type default)
			)
			(layer "B.Fab")
		)
		(pad "1" smd circle
			(at 0.40005 0)
			(size 0 0)
			(layers "B.Cu" "B.Mask" "B.Paste")
			(net "P3V3")
		)
		(pad "2" smd circle
			(at -0.40005 0)
			(size 0 0)
			(layers "B.Cu" "B.Mask" "B.Paste")
			(net "SMB_CPU0_CPU1_APML_BUF1_SCL_R2")
		)
	)
	(footprint ""
		(layer "B.Cu")
		(at 230.886 -232.156 90)
		(property "Reference" "C9"
			(at 0 0 90)
			(layer "B.SilkS")
			(hide yes)
			(effects
				(font
					(size 1.27 1.27)
				)
				(justify mirror)
			)
		)
		(property "Value" ""
			(at 0 0 90)
			(layer "B.Fab")
			(effects
				(font
					(size 1.27 1.27)
				)
				(justify mirror)
			)
		)
		(duplicate_pad_numbers_are_jumpers no)
		(fp_line
			(start 0.7874 -0.4064)
			(end -0.7874 -0.4064)
			(stroke
				(width 0.1524)
				(type default)
			)
			(layer "B.SilkS")
		)
		(fp_line
			(start -0.7874 -0.4064)
			(end -0.7874 0.4064)
			(stroke
				(width 0.1524)
				(type default)
			)
			(layer "B.SilkS")
		)
		(fp_line
			(start 0.7874 0.4064)
			(end 0.7874 -0.4064)
			(stroke
				(width 0.1524)
				(type default)
			)
			(layer "B.SilkS")
		)
		(fp_line
			(start -0.7874 0.4064)
			(end 0.7874 0.4064)
			(stroke
				(width 0.1524)
				(type default)
			)
			(layer "B.SilkS")
		)
		(fp_line
			(start 0.67945 -0.305054)
			(end 0.12065 -0.305054)
			(stroke
				(width 0.1)
				(type default)
			)
			(layer "B.Fab")
		)
		(fp_line
			(start 0.12065 -0.305054)
			(end 0.12065 -0.2794)
			(stroke
				(width 0.1)
				(type default)
			)
			(layer "B.Fab")
		)
		(fp_line
			(start -0.12065 -0.3048)
			(end -0.67945 -0.3048)
			(stroke
				(width 0.1)
				(type default)
			)
			(layer "B.Fab")
		)
		(fp_line
			(start -0.67945 -0.3048)
			(end -0.67945 0.3048)
			(stroke
				(width 0.1)
				(type default)
			)
			(layer "B.Fab")
		)
		(fp_line
			(start 0.12065 -0.2794)
			(end -0.12065 -0.2794)
			(stroke
				(width 0.1)
				(type default)
			)
			(layer "B.Fab")
		)
		(fp_line
			(start -0.12065 -0.2794)
			(end -0.12065 -0.3048)
			(stroke
				(width 0.1)
				(type default)
			)
			(layer "B.Fab")
		)
		(fp_line
			(start 0.12065 0.2794)
			(end 0.12065 0.3048)
			(stroke
				(width 0.1)
				(type default)
			)
			(layer "B.Fab")
		)
		(fp_line
			(start -0.120396 0.2794)
			(end 0.12065 0.2794)
			(stroke
				(width 0.1)
				(type default)
			)
			(layer "B.Fab")
		)
		(fp_line
			(start 0.67945 0.3048)
			(end 0.67945 -0.305054)
			(stroke
				(width 0.1)
				(type default)
			)
			(layer "B.Fab")
		)
		(fp_line
			(start 0.12065 0.3048)
			(end 0.67945 0.3048)
			(stroke
				(width 0.1)
				(type default)
			)
			(layer "B.Fab")
		)
		(fp_line
			(start -0.120396 0.3048)
			(end -0.120396 0.2794)
			(stroke
				(width 0.1)
				(type default)
			)
			(layer "B.Fab")
		)
		(fp_line
			(start -0.67945 0.3048)
			(end -0.120396 0.3048)
			(stroke
				(width 0.1)
				(type default)
			)
			(layer "B.Fab")
		)
		(pad "1" smd circle
			(at 0.40005 0 270)
			(size 0 0)
			(layers "B.Cu" "B.Mask" "B.Paste")
			(net "I3C_MUX_CPU0_VIO")
		)
		(pad "2" smd circle
			(at -0.40005 0 270)
			(size 0 0)
			(layers "B.Cu" "B.Mask" "B.Paste")
			(net "GND")
		)
	)
	(footprint ""
		(layer "B.Cu")
		(at 314.965588 2.542794 180)
		(property "Reference" "J70"
			(at 4.55422 -0.940308 270)
			(unlocked yes)
			(layer "B.SilkS")
			(effects
				(font
					(size 0.7874 0.5842)
					(thickness 0.1524)
				)
				(justify left mirror)
			)
		)
		(property "Value" ""
			(at 0 0 0)
			(layer "B.Fab")
			(effects
				(font
					(size 1.27 1.27)
				)
				(justify mirror)
			)
		)
		(duplicate_pad_numbers_are_jumpers no)
		(fp_line
			(start 1.2192 2.06756)
			(end 1.2192 -2.06756)
			(stroke
				(width 0.1524)
				(type default)
			)
			(layer "B.SilkS")
		)
		(fp_line
			(start 1.2192 -2.06756)
			(end -1.2192 -2.06756)
			(stroke
				(width 0.1524)
				(type default)
			)
			(layer "B.SilkS")
		)
		(fp_line
			(start -1.2192 2.06756)
			(end 1.2192 2.06756)
			(stroke
				(width 0.1524)
				(type default)
			)
			(layer "B.SilkS")
		)
		(fp_line
			(start -1.2192 -2.06756)
			(end -1.2192 2.06756)
			(stroke
				(width 0.1524)
				(type default)
			)
			(layer "B.SilkS")
		)
		(pad "" np_thru_hole circle
			(at -3.4671 -1.27 90)
			(size 1.0414 1.0414)
			(drill 1.0414)
			(layers "*.Cu" "*.Mask")
			(clearance 0.381)
			(thermal_gap 0.381)
		)
		(pad "" np_thru_hole circle
			(at -3.4671 1.27 90)
			(size 1.0414 1.0414)
			(drill 1.0414)
			(layers "*.Cu" "*.Mask")
			(clearance 0.381)
			(thermal_gap 0.381)
		)
		(pad "" np_thru_hole circle
			(at 2.8829 -1.27 90)
			(size 1.0414 1.0414)
			(drill 1.0414)
			(layers "*.Cu" "*.Mask")
			(clearance 0.381)
			(thermal_gap 0.381)
		)
		(pad "" np_thru_hole circle
			(at 2.8829 1.27 90)
			(size 1.0414 1.0414)
			(drill 1.0414)
			(layers "*.Cu" "*.Mask")
			(clearance 0.381)
			(thermal_gap 0.381)
		)
		(pad "1" smd rect
			(at -0.8255 -0.249936 90)
			(size 0.3048 0.508)
			(layers "B.Cu" "B.Mask" "B.Paste")
			(net "DELTA_L_85_5INCH_BOT_DN")
		)
		(pad "2" smd rect
			(at -0.8255 0.249936 90)
			(size 0.3048 0.508)
			(layers "B.Cu" "B.Mask" "B.Paste")
			(net "DELTA_L_85_5INCH_BOT_DP")
		)
		(pad "3" smd circle
			(at 0 0)
			(size 0 0)
			(layers "B.Cu" "B.Mask" "B.Paste")
			(net "DELTA_L_GND_1")
		)
		(zone
			(layers "F.Cu" "B.Cu" "In1.Cu" "In2.Cu" "In3.Cu" "In4.Cu" "In5.Cu" "In6.Cu"
				"In7.Cu" "In8.Cu" "In9.Cu" "In10.Cu" "In11.Cu" "In12.Cu" "In13.Cu" "In14.Cu"
				"In15.Cu" "In16.Cu"
			)
			(hatch none 0.5)
			(connect_pads
				(clearance 0)
			)
			(min_thickness 0.25)
			(keepout
				(tracks not_allowed)
				(vias allowed)
				(pads allowed)
				(copperpour not_allowed)
				(footprints allowed)
			)
			(placement
				(enabled no)
				(sheetname "")
			)
			(fill
				(thermal_gap 0.5)
				(thermal_bridge_width 0.5)
				(island_removal_mode 0)
			)
			(polygon
				(pts
					(arc
						(start 313.009788 1.272794)
						(mid 311.155588 1.272794)
						(end 313.009788 1.272794)
					)
				)
			)
		)
		(zone
			(layers "F.Cu" "B.Cu" "In1.Cu" "In2.Cu" "In3.Cu" "In4.Cu" "In5.Cu" "In6.Cu"
				"In7.Cu" "In8.Cu" "In9.Cu" "In10.Cu" "In11.Cu" "In12.Cu" "In13.Cu" "In14.Cu"
				"In15.Cu" "In16.Cu"
			)
			(hatch none 0.5)
			(connect_pads
				(clearance 0)
			)
			(min_thickness 0.25)
			(keepout
				(tracks not_allowed)
				(vias allowed)
				(pads allowed)
				(copperpour not_allowed)
				(footprints allowed)
			)
			(placement
				(enabled no)
				(sheetname "")
			)
			(fill
				(thermal_gap 0.5)
				(thermal_bridge_width 0.5)
				(island_removal_mode 0)
			)
			(polygon
				(pts
					(arc
						(start 313.009788 3.812794)
						(mid 311.155588 3.812794)
						(end 313.009788 3.812794)
					)
				)
			)
		)
		(zone
			(layers "F.Cu" "B.Cu" "In1.Cu" "In2.Cu" "In3.Cu" "In4.Cu" "In5.Cu" "In6.Cu"
				"In7.Cu" "In8.Cu" "In9.Cu" "In10.Cu" "In11.Cu" "In12.Cu" "In13.Cu" "In14.Cu"
				"In15.Cu" "In16.Cu"
			)
			(hatch none 0.5)
			(connect_pads
				(clearance 0)
			)
			(min_thickness 0.25)
			(keepout
				(tracks not_allowed)
				(vias allowed)
				(pads allowed)
				(copperpour not_allowed)
				(footprints allowed)
			)
			(placement
				(enabled no)
				(sheetname "")
			)
			(fill
				(thermal_gap 0.5)
				(thermal_bridge_width 0.5)
				(island_removal_mode 0)
			)
			(polygon
				(pts
					(arc
						(start 319.359788 1.272794)
						(mid 317.505588 1.272794)
						(end 319.359788 1.272794)
					)
				)
			)
		)
		(zone
			(layers "F.Cu" "B.Cu" "In1.Cu" "In2.Cu" "In3.Cu" "In4.Cu" "In5.Cu" "In6.Cu"
				"In7.Cu" "In8.Cu" "In9.Cu" "In10.Cu" "In11.Cu" "In12.Cu" "In13.Cu" "In14.Cu"
				"In15.Cu" "In16.Cu"
			)
			(hatch none 0.5)
			(connect_pads
				(clearance 0)
			)
			(min_thickness 0.25)
			(keepout
				(tracks not_allowed)
				(vias allowed)
				(pads allowed)
				(copperpour not_allowed)
				(footprints allowed)
			)
			(placement
				(enabled no)
				(sheetname "")
			)
			(fill
				(thermal_gap 0.5)
				(thermal_bridge_width 0.5)
				(island_removal_mode 0)
			)
			(polygon
				(pts
					(arc
						(start 319.359788 3.812794)
						(mid 317.505588 3.812794)
						(end 319.359788 3.812794)
					)
				)
			)
		)
		(zone
			(layer "B.Cu")
			(hatch none 0.5)
			(connect_pads
				(clearance 0)
			)
			(min_thickness 0.25)
			(keepout
				(tracks not_allowed)
				(vias allowed)
				(pads allowed)
				(copperpour not_allowed)
				(footprints allowed)
			)
			(placement
				(enabled no)
				(sheetname "")
			)
			(fill
				(thermal_gap 0.5)
				(thermal_bridge_width 0.5)
				(island_removal_mode 0)
			)
			(polygon
				(pts
					(xy 316.083188 3.091434) (xy 316.083188 2.99593) (xy 315.486288 2.99593) (xy 315.486288 2.58953)
					(xy 316.083188 2.58953) (xy 316.083188 2.496058) (xy 315.486288 2.496058) (xy 315.486288 2.089658)
					(xy 316.083188 2.089658) (xy 316.083188 1.994154) (xy 315.384688 1.994154) (xy 315.384688 3.091434)
				)
			)
		)
	)
	(footprint ""
		(layer "B.Cu")
		(at 393.070588 -180.078634 90)
		(property "Reference" "PR351"
			(at 0 0 90)
			(layer "B.SilkS")
			(hide yes)
			(effects
				(font
					(size 1.27 1.27)
				)
				(justify mirror)
			)
		)
		(property "Value" ""
			(at 0 0 90)
			(layer "B.Fab")
			(effects
				(font
					(size 1.27 1.27)
				)
				(justify mirror)
			)
		)
		(duplicate_pad_numbers_are_jumpers no)
		(fp_line
			(start 0.7874 -0.4064)
			(end -0.7874 -0.4064)
			(stroke
				(width 0.1524)
				(type default)
			)
			(layer "B.SilkS")
		)
		(fp_line
			(start -0.7874 -0.4064)
			(end -0.7874 0.4064)
			(stroke
				(width 0.1524)
				(type default)
			)
			(layer "B.SilkS")
		)
		(fp_line
			(start 0.7874 0.4064)
			(end 0.7874 -0.4064)
			(stroke
				(width 0.1524)
				(type default)
			)
			(layer "B.SilkS")
		)
		(fp_line
			(start -0.7874 0.4064)
			(end 0.7874 0.4064)
			(stroke
				(width 0.1524)
				(type default)
			)
			(layer "B.SilkS")
		)
		(fp_line
			(start 0.67945 -0.305054)
			(end 0.12065 -0.305054)
			(stroke
				(width 0.1)
				(type default)
			)
			(layer "B.Fab")
		)
		(fp_line
			(start 0.12065 -0.305054)
			(end 0.12065 -0.2794)
			(stroke
				(width 0.1)
				(type default)
			)
			(layer "B.Fab")
		)
		(fp_line
			(start -0.12065 -0.3048)
			(end -0.67945 -0.3048)
			(stroke
				(width 0.1)
				(type default)
			)
			(layer "B.Fab")
		)
		(fp_line
			(start -0.67945 -0.3048)
			(end -0.67945 0.3048)
			(stroke
				(width 0.1)
				(type default)
			)
			(layer "B.Fab")
		)
		(fp_line
			(start 0.12065 -0.2794)
			(end -0.12065 -0.2794)
			(stroke
				(width 0.1)
				(type default)
			)
			(layer "B.Fab")
		)
		(fp_line
			(start -0.12065 -0.2794)
			(end -0.12065 -0.3048)
			(stroke
				(width 0.1)
				(type default)
			)
			(layer "B.Fab")
		)
		(fp_line
			(start 0.12065 0.2794)
			(end 0.12065 0.3048)
			(stroke
				(width 0.1)
				(type default)
			)
			(layer "B.Fab")
		)
		(fp_line
			(start -0.120396 0.2794)
			(end 0.12065 0.2794)
			(stroke
				(width 0.1)
				(type default)
			)
			(layer "B.Fab")
		)
		(fp_line
			(start 0.67945 0.3048)
			(end 0.67945 -0.305054)
			(stroke
				(width 0.1)
				(type default)
			)
			(layer "B.Fab")
		)
		(fp_line
			(start 0.12065 0.3048)
			(end 0.67945 0.3048)
			(stroke
				(width 0.1)
				(type default)
			)
			(layer "B.Fab")
		)
		(fp_line
			(start -0.120396 0.3048)
			(end -0.120396 0.2794)
			(stroke
				(width 0.1)
				(type default)
			)
			(layer "B.Fab")
		)
		(fp_line
			(start -0.67945 0.3048)
			(end -0.120396 0.3048)
			(stroke
				(width 0.1)
				(type default)
			)
			(layer "B.Fab")
		)
		(pad "1" smd circle
			(at 0.40005 0 270)
			(size 0 0)
			(layers "B.Cu" "B.Mask" "B.Paste")
			(net "PVDDCR_CPU0_P0_VOS4")
		)
		(pad "2" smd circle
			(at -0.40005 0 270)
			(size 0 0)
			(layers "B.Cu" "B.Mask" "B.Paste")
			(net "PVDDCR_CPU0_P0")
		)
	)
)
